# T6G (Grand Teton) — schematic netlist excerpt (pin names and nets, part order shuffled) for the footprints in the layout excerpt that follows; sources: Cadence DE-HDL packaged netlist, KiCad conversion of 04192023_DAF0TMB3IC0_F0TG_MB_C_brd_V02_OCP.brd

J67  SCONN288_DDR506112002KQ  IO  pkg DDR288S_1-1VXC  page 97
  VIN_BULK0  = P12V_MEM_CPU0
  RFU0  = NC
  VIN_MGMT  = P3V3_AUX
  HSCL  = I3C_SPD_DDRL_CPU0_SCL
  HSDA  = I3C_SPD_DDRL_CPU0_SDA
  VSS0  = GND
  DQ0_A  = M_L_CPU0_SA_DQ<0>
  VSS1  = GND
  DQ1_A  = M_L_CPU0_SA_DQ<1>
  VSS2  = GND
  DQS0_A_T  = M_L_CPU0_SA_DQS_DP<0>
  DQS0_A_C  = M_L_CPU0_SA_DQS_DN<0>
  VSS3  = GND
  DQ4_A  = M_L_CPU0_SA_DQ<4>
  VSS4  = GND
  DQ5_A  = M_L_CPU0_SA_DQ<5>
  VSS5  = GND
  DQ8_A  = M_L_CPU0_SA_DQ<8>
  VSS6  = GND
  DQ9_A  = M_L_CPU0_SA_DQ<9>
  VSS7  = GND
  DQS1_A_T  = M_L_CPU0_SA_DQS_DP<1>
  DQS1_A_C  = M_L_CPU0_SA_DQS_DN<1>
  VSS8  = GND
  DQ12_A  = M_L_CPU0_SA_DQ<12>
  VSS9  = GND
  DQ13_A  = M_L_CPU0_SA_DQ<13>
  VSS10  = GND
  DQ16_A  = M_L_CPU0_SA_DQ<16>
  VSS11  = GND
  DQ17_A  = M_L_CPU0_SA_DQ<17>
  VSS12  = GND
  DQS2_A_T  = M_L_CPU0_SA_DQS_DP<2>
  DQS2_A_C  = M_L_CPU0_SA_DQS_DN<2>
  VSS13  = GND
  DQ20_A  = M_L_CPU0_SA_DQ<20>
  VSS14  = GND
  DQ21_A  = M_L_CPU0_SA_DQ<21>
  VSS15  = GND
  DQ24_A  = M_L_CPU0_SA_DQ<24>
  VSS16  = GND
  DQ25_A  = M_L_CPU0_SA_DQ<25>
  VSS17  = GND
  DQS3_A_T  = M_L_CPU0_SA_DQS_DP<3>
  DQS3_A_C  = M_L_CPU0_SA_DQS_DN<3>
  VSS18  = GND
  DQ28_A  = M_L_CPU0_SA_DQ<28>
  VSS19  = GND
  DQ29_A  = M_L_CPU0_SA_DQ<29>
  VSS20  = GND
  CB0_A  = M_L_CPU0_SA_CB<0>
  VSS21  = GND
  CB1_A  = M_L_CPU0_SA_CB<1>
  VSS22  = GND
  DQS4_A_T  = M_L_CPU0_SA_DQS_DP<4>
  DQS4_A_C  = M_L_CPU0_SA_DQS_DN<4>
  VSS23  = GND
  CB4_A  = M_L_CPU0_SA_CB<4>
  VSS24  = GND
  CB5_A  = M_L_CPU0_SA_CB<5>
  VSS25  = GND
  ALERT_N  = M_L_CPU0_ALERT_N
  VSS26  = GND
  CS0_A_N  = M_L_CPU0_SA_CS_N<0>
  VSS27  = GND
  CA0_A  = M_L_CPU0_SA_CA<0>
  VSS28  = GND
  CA2_A  = M_L_CPU0_SA_CA<2>
  VSS29  = GND
  CA4_A  = M_L_CPU0_SA_CA<4>
  VSS30  = GND
  CA6_A  = M_L_CPU0_SA_CA<6>
  VSS31  = GND
  PAR_A  = M_L_CPU0_SA_PAR
  VSS32  = GND
  CA0_B  = M_L_CPU0_SB_CA<0>
  VSS33  = GND
  CA2_B  = M_L_CPU0_SB_CA<2>
  VSS34  = GND
  CA4_B  = M_L_CPU0_SB_CA<4>
  VSS35  = GND
  CA6_B  = M_L_CPU0_SB_CA<6>
  VSS36  = GND
  CS0_B_N  = M_L_CPU0_SB_CS_N<0>
  VSS37  = GND
  \lbd||rsp_a_n\  = M_L_CPU0_SA_RSP<0>
  \lbs||rsp_b_n\  = M_L_CPU0_SB_RSP<0>
  VSS38  = GND
  CB4_B  = M_L_CPU0_SB_CB<4>
  VSS39  = GND
  CB5_B  = M_L_CPU0_SB_CB<5>
  VSS40  = GND
  \dqs9_b_t||tdqs9_b_t||dbi4_b_n\  = M_L_CPU0_SB_DQS_DP<9>
  \dqs9_b_c||tdqs9_b_c\  = M_L_CPU0_SB_DQS_DN<9>
  VSS41  = GND
  CB0_B  = M_L_CPU0_SB_CB<0>
  VSS42  = GND
  CB1_B  = M_L_CPU0_SB_CB<1>
  VSS43  = GND
  DQ0_B  = M_L_CPU0_SB_DQ<0>
  VSS44  = GND
  DQ1_B  = M_L_CPU0_SB_DQ<1>
  VSS45  = GND
  DQS0_B_T  = M_L_CPU0_SB_DQS_DP<0>
  DQS0_B_C  = M_L_CPU0_SB_DQS_DN<0>
  VSS46  = GND
  DQ4_B  = M_L_CPU0_SB_DQ<4>
  VSS47  = GND
  DQ5_B  = M_L_CPU0_SB_DQ<5>
  VSS48  = GND
  DQ8_B  = M_L_CPU0_SB_DQ<8>
  VSS49  = GND
  DQ9_B  = M_L_CPU0_SB_DQ<9>
  VSS50  = GND
  DQS1_B_T  = M_L_CPU0_SB_DQS_DP<1>
  DQS1_B_C  = M_L_CPU0_SB_DQS_DN<1>
  VSS51  = GND
  DQ12_B  = M_L_CPU0_SB_DQ<12>
  VSS52  = GND
  DQ13_B  = M_L_CPU0_SB_DQ<13>
  VSS53  = GND
  DQ16_B  = M_L_CPU0_SB_DQ<16>
  VSS54  = GND
  DQ17_B  = M_L_CPU0_SB_DQ<17>
  VSS55  = GND
  DQS2_B_T  = M_L_CPU0_SB_DQS_DP<2>
  DQS2_B_C  = M_L_CPU0_SB_DQS_DN<2>
  VSS56  = GND
  DQ20_B  = M_L_CPU0_SB_DQ<20>
  VSS57  = GND
  DQ21_B  = M_L_CPU0_SB_DQ<21>
  VSS58  = GND
  DQ24_B  = M_L_CPU0_SB_DQ<24>
  VSS59  = GND
  DQ25_B  = M_L_CPU0_SB_DQ<25>
  VSS60  = GND
  DQS3_B_T  = M_L_CPU0_SB_DQS_DP<3>
  DQS3_B_C  = M_L_CPU0_SB_DQS_DN<3>
  VSS61  = GND
  DQ28_B  = M_L_CPU0_SB_DQ<28>
  VSS62  = GND
  DQ29_B  = M_L_CPU0_SB_DQ<29>
  VSS63  = GND
  RFU1  = NC
  VIN_BULK1  = P12V_MEM_CPU0
  VIN_BULK2  = P12V_MEM_CPU0
  \pwr_good||fail_n\  = PWRGD_CHL_CPU0_DIMM
  HAS  = PD_CHL_CPU0_DIMM_SAA
  RFU2  = NC
  RFU3  = NC
  VSS64  = GND
  DQ2_A  = M_L_CPU0_SA_DQ<2>
  VSS65  = GND
  DQ3_A  = M_L_CPU0_SA_DQ<3>
  VSS66  = GND
  \dqs5_a_c||tdqs5_a_c||dqs5_a_t||tdqs5_a_t\  = M_L_CPU0_SA_DQS_DN<5>
  \dqs5_a_t||tdqs5_a_t\  = M_L_CPU0_SA_DQS_DP<5>
  VSS67  = GND
  DQ6_A  = M_L_CPU0_SA_DQ<6>
  VSS68  = GND
  DQ7_A  = M_L_CPU0_SA_DQ<7>
  VSS69  = GND
  DQ10_A  = M_L_CPU0_SA_DQ<10>
  VSS70  = GND
  DQ11_A  = M_L_CPU0_SA_DQ<11>
  VSS71  = GND
  \dqs6_a_c||tdqs6_a_c||dqs6_a_t||tdqs6_a_t\  = M_L_CPU0_SA_DQS_DN<6>
  \dqs6_a_t||tdqs6_a_t\  = M_L_CPU0_SA_DQS_DP<6>
  VSS72  = GND
  DQ14_A  = M_L_CPU0_SA_DQ<14>
  VSS73  = GND
  DQ15_A  = M_L_CPU0_SA_DQ<15>
  VSS74  = GND
  DQ18_A  = M_L_CPU0_SA_DQ<18>
  VSS75  = GND
  DQ19_A  = M_L_CPU0_SA_DQ<19>
  VSS76  = GND
  \dqs7_a_c||tdqs7_a_c\  = M_L_CPU0_SA_DQS_DN<7>
  \dqs7_a_t||tdqs7_a_t\  = M_L_CPU0_SA_DQS_DP<7>
  VSS77  = GND
  DQ22_A  = M_L_CPU0_SA_DQ<22>
  VSS78  = GND
  DQ23_A  = M_L_CPU0_SA_DQ<23>
  VSS79  = GND
  DQ26_A  = M_L_CPU0_SA_DQ<26>
  VSS80  = GND
  DQ27_A  = M_L_CPU0_SA_DQ<27>
  VSS81  = GND
  \dqs8_a_c||tdqs8_a_c\  = M_L_CPU0_SA_DQS_DN<8>
  \dqs8_a_t||tdqs8_a_t\  = M_L_CPU0_SA_DQS_DP<8>
  VSS82  = GND
  DQ30_A  = M_L_CPU0_SA_DQ<30>
  VSS83  = GND
  DQ31_A  = M_L_CPU0_SA_DQ<31>
  VSS84  = GND
  CB2_A  = M_L_CPU0_SA_CB<2>
  VSS85  = GND
  CB3_A  = M_L_CPU0_SA_CB<3>
  VSS86  = GND
  \dqs9_a_c||tdqs9_a_c\  = M_L_CPU0_SA_DQS_DN<9>
  \dqs9_a_t||tdqs9_a_t\  = M_L_CPU0_SA_DQS_DP<9>
  VSS87  = GND
  CB6_A  = M_L_CPU0_SA_CB<6>
  VSS88  = GND
  CB7_A  = M_L_CPU0_SA_CB<7>
  VSS89  = GND
  RESET_N  = M_L_CPU0_RESET_N
  VSS90  = GND
  CS1_A_N  = M_L_CPU0_SA_CS_N<1>
  VSS91  = GND
  CA1_A  = M_L_CPU0_SA_CA<1>
  VSS92  = GND
  CA3_A  = M_L_CPU0_SA_CA<3>
  VSS93  = GND
  CA5_A  = M_L_CPU0_SA_CA<5>
  VSS94  = GND
  CK_T  = M_L_CPU0_CLK_DP<0>
  CK_C  = M_L_CPU0_CLK_DN<0>
  VSS95  = GND
  RFU4  = NC
  CA1_B  = M_L_CPU0_SB_CA<1>
  VSS96  = GND
  CA3_B  = M_L_CPU0_SB_CA<3>
  VSS97  = GND
  CA5_B  = M_L_CPU0_SB_CA<5>
  VSS98  = GND
  PAR_B  = M_L_CPU0_SB_PAR
  VSS99  = GND
  CS1_B_N  = M_L_CPU0_SB_CS_N<1>
  VSS100  = GND
  RFU5  = NC
  RFU6  = NC
  VSS101  = GND
  CB6_B  = M_L_CPU0_SB_CB<6>
  VSS102  = GND
  CB7_B  = M_L_CPU0_SB_CB<7>
  VSS103  = GND
  DQS4_B_C  = M_L_CPU0_SB_DQS_DN<4>
  DQS4_B_T  = M_L_CPU0_SB_DQS_DP<4>
  VSS104  = GND
  CB2_B  = M_L_CPU0_SB_CB<2>
  VSS105  = GND
  CB3_B  = M_L_CPU0_SB_CB<3>
  VSS106  = GND
  DQ2_B  = M_L_CPU0_SB_DQ<2>
  VSS107  = GND
  DQ3_B  = M_L_CPU0_SB_DQ<3>
  VSS108  = GND
  \dqs5_b_c||tdqs5_b_c\  = M_L_CPU0_SB_DQS_DN<5>
  \dqs5_b_t||tdqs5_b_t\  = M_L_CPU0_SB_DQS_DP<5>
  VSS109  = GND
  DQ6_B  = M_L_CPU0_SB_DQ<6>
  VSS110  = GND
  DQ7_B  = M_L_CPU0_SB_DQ<7>
  VSS111  = GND
  DQ10_B  = M_L_CPU0_SB_DQ<10>
  VSS112  = GND
  DQ11_B  = M_L_CPU0_SB_DQ<11>
  VSS113  = GND
  \dqs6_b_c||tdqs6_b_c\  = M_L_CPU0_SB_DQS_DN<6>
  \dqs6_b_t||tdqs6_b_t\  = M_L_CPU0_SB_DQS_DP<6>
  VSS114  = GND
  DQ14_B  = M_L_CPU0_SB_DQ<14>
  VSS115  = GND
  DQ15_B  = M_L_CPU0_SB_DQ<15>
  VSS116  = GND
  DQ18_B  = M_L_CPU0_SB_DQ<18>
  VSS117  = GND
  DQ19_B  = M_L_CPU0_SB_DQ<19>
  VSS118  = GND
  \dqs7_b_c||tdqs7_b_c\  = M_L_CPU0_SB_DQS_DN<7>
  \dqs7_b_t||tdqs7_b_t\  = M_L_CPU0_SB_DQS_DP<7>
  VSS119  = GND
  DQ22_B  = M_L_CPU0_SB_DQ<22>
  VSS120  = GND
  DQ23_B  = M_L_CPU0_SB_DQ<23>
  VSS121  = GND
  DQ26_B  = M_L_CPU0_SB_DQ<26>
  VSS122  = GND
  DQ27_B  = M_L_CPU0_SB_DQ<27>
  VSS123  = GND
  \dqs8_b_c||tdqs8_b_c\  = M_L_CPU0_SB_DQS_DN<8>
  \dqs8_b_t||tdqs8_b_t\  = M_L_CPU0_SB_DQS_DP<8>
  VSS124  = GND
  DQ30_B  = M_L_CPU0_SB_DQ<30>
  VSS125  = GND
  DQ31_B  = M_L_CPU0_SB_DQ<31>
  VSS126  = GND
  G1  = GND
  G2  = GND
  G3  = GND

(kicad_pcb
	(version 20260206)
	(generator "pcbnew")
	(generator_version "10.0")
	(general
		(thickness 1.6)
		(legacy_teardrops no)
	)
	(paper "A4")
	(title_block
		(title "04192023_DAF0TMB3IC0_F0TG_MB_C_brd_V02_OCP.brd")
		(comment 1 "Grand Teton / footprint 3721 of 8354 (J67), pads 93-138 of 291")
	)
	(layers
		(0 "F.Cu" signal "TOP")
		(4 "In1.Cu" signal "GND")
		(6 "In2.Cu" signal "IN1")
		(8 "In3.Cu" signal "GND1")
		(10 "In4.Cu" signal "IN2")
		(12 "In5.Cu" signal "GND2")
		(14 "In6.Cu" signal "IN3")
		(16 "In7.Cu" signal "GND3")
		(18 "In8.Cu" signal "VCC")
		(20 "In9.Cu" signal "VCC1")
		(22 "In10.Cu" signal "GND4")
		(24 "In11.Cu" signal "IN4")
		(26 "In12.Cu" signal "GND5")
		(28 "In13.Cu" signal "IN5")
		(30 "In14.Cu" signal "GND6")
		(32 "In15.Cu" signal "IN6")
		(34 "In16.Cu" signal "GND7")
		(2 "B.Cu" signal "BOTTOM")
		(9 "F.Adhes" user "F.Adhesive")
		(11 "B.Adhes" user "B.Adhesive")
		(13 "F.Paste" user "Package Geometry/Pastemask Top")
		(15 "B.Paste" user "Package Geometry/Pastemask Bottom")
		(5 "F.SilkS" user "Ref Des/Silkscreen Top")
		(7 "B.SilkS" user "Ref Des/Silkscreen Bottom")
		(1 "F.Mask" user "Board Geometry/Soldermask Top")
		(3 "B.Mask" user "Board Geometry/Soldermask Bottom")
		(17 "Dwgs.User" user "User.Drawings")
		(19 "Cmts.User" user "User.Comments")
		(21 "Eco1.User" user "User.Eco1")
		(23 "Eco2.User" user "User.Eco2")
		(25 "Edge.Cuts" user "Board Geometry/Outline")
		(27 "Margin" user)
		(31 "F.CrtYd" user "Package Geometry/Place Bound Top")
		(29 "B.CrtYd" user "Package Geometry/Place Bound Bottom")
		(35 "F.Fab" user "Ref Des/Assembly Top")
		(33 "B.Fab" user "Ref Des/Assembly Bottom")
	)
	(footprint ""
		(layer "F.Cu")
		(at 452.138034 -255.560068 180)
		(property "Reference" "J67"
			(at 2.380488 -81.709768 0)
			(unlocked yes)
			(layer "F.SilkS")
			(effects
				(font
					(size 0.7874 0.5842)
					(thickness 0.1524)
				)
			)
		)
		(property "Value" ""
			(at 0 0 180)
			(layer "F.Fab")
			(effects
				(font
					(size 1.27 1.27)
				)
			)
		)
		(duplicate_pad_numbers_are_jumpers no)
		(pad "93" smd rect
			(at -2.050034 19.975068 90)
			(size 0.519938 1.4986)
			(layers "F.Cu" "F.Mask" "F.Paste")
			(net "M_L_CPU0_SB_DQS_DP<9>")
		)
		(pad "94" smd rect
			(at -2.050034 20.824952 90)
			(size 0.519938 1.4986)
			(layers "F.Cu" "F.Mask" "F.Paste")
			(net "M_L_CPU0_SB_DQS_DN<9>")
		)
		(pad "95" smd rect
			(at -2.050034 21.67509 90)
			(size 0.519938 1.4986)
			(layers "F.Cu" "F.Mask" "F.Paste")
			(net "GND")
		)
		(pad "96" smd rect
			(at -2.050034 22.524974 90)
			(size 0.519938 1.4986)
			(layers "F.Cu" "F.Mask" "F.Paste")
			(net "M_L_CPU0_SB_CB<0>")
		)
		(pad "97" smd rect
			(at -2.050034 23.375112 90)
			(size 0.519938 1.4986)
			(layers "F.Cu" "F.Mask" "F.Paste")
			(net "GND")
		)
		(pad "98" smd rect
			(at -2.050034 24.224996 90)
			(size 0.519938 1.4986)
			(layers "F.Cu" "F.Mask" "F.Paste")
			(net "M_L_CPU0_SB_CB<1>")
		)
		(pad "99" smd rect
			(at -2.050034 25.07488 90)
			(size 0.519938 1.4986)
			(layers "F.Cu" "F.Mask" "F.Paste")
			(net "GND")
		)
		(pad "100" smd rect
			(at -2.050034 25.925018 90)
			(size 0.519938 1.4986)
			(layers "F.Cu" "F.Mask" "F.Paste")
			(net "M_L_CPU0_SB_DQ<0>")
		)
		(pad "101" smd rect
			(at -2.050034 26.774902 90)
			(size 0.519938 1.4986)
			(layers "F.Cu" "F.Mask" "F.Paste")
			(net "GND")
		)
		(pad "102" smd rect
			(at -2.050034 27.62504 90)
			(size 0.519938 1.4986)
			(layers "F.Cu" "F.Mask" "F.Paste")
			(net "M_L_CPU0_SB_DQ<1>")
		)
		(pad "103" smd rect
			(at -2.050034 28.474924 90)
			(size 0.519938 1.4986)
			(layers "F.Cu" "F.Mask" "F.Paste")
			(net "GND")
		)
		(pad "104" smd rect
			(at -2.050034 29.325062 90)
			(size 0.519938 1.4986)
			(layers "F.Cu" "F.Mask" "F.Paste")
			(net "M_L_CPU0_SB_DQS_DP<0>")
		)
		(pad "105" smd rect
			(at -2.050034 30.174946 90)
			(size 0.519938 1.4986)
			(layers "F.Cu" "F.Mask" "F.Paste")
			(net "M_L_CPU0_SB_DQS_DN<0>")
		)
		(pad "106" smd rect
			(at -2.050034 31.025084 90)
			(size 0.519938 1.4986)
			(layers "F.Cu" "F.Mask" "F.Paste")
			(net "GND")
		)
		(pad "107" smd rect
			(at -2.050034 31.874968 90)
			(size 0.519938 1.4986)
			(layers "F.Cu" "F.Mask" "F.Paste")
			(net "M_L_CPU0_SB_DQ<4>")
		)
		(pad "108" smd rect
			(at -2.050034 32.725106 90)
			(size 0.519938 1.4986)
			(layers "F.Cu" "F.Mask" "F.Paste")
			(net "GND")
		)
		(pad "109" smd rect
			(at -2.050034 33.57499 90)
			(size 0.519938 1.4986)
			(layers "F.Cu" "F.Mask" "F.Paste")
			(net "M_L_CPU0_SB_DQ<5>")
		)
		(pad "110" smd rect
			(at -2.050034 34.425128 90)
			(size 0.519938 1.4986)
			(layers "F.Cu" "F.Mask" "F.Paste")
			(net "GND")
		)
		(pad "111" smd rect
			(at -2.050034 35.275012 90)
			(size 0.519938 1.4986)
			(layers "F.Cu" "F.Mask" "F.Paste")
			(net "M_L_CPU0_SB_DQ<8>")
		)
		(pad "112" smd rect
			(at -2.050034 36.124896 90)
			(size 0.519938 1.4986)
			(layers "F.Cu" "F.Mask" "F.Paste")
			(net "GND")
		)
		(pad "113" smd rect
			(at -2.050034 36.975034 90)
			(size 0.519938 1.4986)
			(layers "F.Cu" "F.Mask" "F.Paste")
			(net "M_L_CPU0_SB_DQ<9>")
		)
		(pad "114" smd rect
			(at -2.050034 37.824918 90)
			(size 0.519938 1.4986)
			(layers "F.Cu" "F.Mask" "F.Paste")
			(net "GND")
		)
		(pad "115" smd rect
			(at -2.050034 38.675056 90)
			(size 0.519938 1.4986)
			(layers "F.Cu" "F.Mask" "F.Paste")
			(net "M_L_CPU0_SB_DQS_DP<1>")
		)
		(pad "116" smd rect
			(at -2.050034 39.52494 90)
			(size 0.519938 1.4986)
			(layers "F.Cu" "F.Mask" "F.Paste")
			(net "M_L_CPU0_SB_DQS_DN<1>")
		)
		(pad "117" smd rect
			(at -2.050034 40.375078 90)
			(size 0.519938 1.4986)
			(layers "F.Cu" "F.Mask" "F.Paste")
			(net "GND")
		)
		(pad "118" smd rect
			(at -2.050034 41.224962 90)
			(size 0.519938 1.4986)
			(layers "F.Cu" "F.Mask" "F.Paste")
			(net "M_L_CPU0_SB_DQ<12>")
		)
		(pad "119" smd rect
			(at -2.050034 42.0751 90)
			(size 0.519938 1.4986)
			(layers "F.Cu" "F.Mask" "F.Paste")
			(net "GND")
		)
		(pad "120" smd rect
			(at -2.050034 42.924984 90)
			(size 0.519938 1.4986)
			(layers "F.Cu" "F.Mask" "F.Paste")
			(net "M_L_CPU0_SB_DQ<13>")
		)
		(pad "121" smd rect
			(at -2.050034 43.775122 90)
			(size 0.519938 1.4986)
			(layers "F.Cu" "F.Mask" "F.Paste")
			(net "GND")
		)
		(pad "122" smd rect
			(at -2.050034 44.625006 90)
			(size 0.519938 1.4986)
			(layers "F.Cu" "F.Mask" "F.Paste")
			(net "M_L_CPU0_SB_DQ<16>")
		)
		(pad "123" smd rect
			(at -2.050034 45.47489 90)
			(size 0.519938 1.4986)
			(layers "F.Cu" "F.Mask" "F.Paste")
			(net "GND")
		)
		(pad "124" smd rect
			(at -2.050034 46.325028 90)
			(size 0.519938 1.4986)
			(layers "F.Cu" "F.Mask" "F.Paste")
			(net "M_L_CPU0_SB_DQ<17>")
		)
		(pad "125" smd rect
			(at -2.050034 47.174912 90)
			(size 0.519938 1.4986)
			(layers "F.Cu" "F.Mask" "F.Paste")
			(net "GND")
		)
		(pad "126" smd rect
			(at -2.050034 48.02505 90)
			(size 0.519938 1.4986)
			(layers "F.Cu" "F.Mask" "F.Paste")
			(net "M_L_CPU0_SB_DQS_DP<2>")
		)
		(pad "127" smd rect
			(at -2.050034 48.874934 90)
			(size 0.519938 1.4986)
			(layers "F.Cu" "F.Mask" "F.Paste")
			(net "M_L_CPU0_SB_DQS_DN<2>")
		)
		(pad "128" smd rect
			(at -2.050034 49.725072 90)
			(size 0.519938 1.4986)
			(layers "F.Cu" "F.Mask" "F.Paste")
			(net "GND")
		)
		(pad "129" smd rect
			(at -2.050034 50.574956 90)
			(size 0.519938 1.4986)
			(layers "F.Cu" "F.Mask" "F.Paste")
			(net "M_L_CPU0_SB_DQ<20>")
		)
		(pad "130" smd rect
			(at -2.050034 51.425094 90)
			(size 0.519938 1.4986)
			(layers "F.Cu" "F.Mask" "F.Paste")
			(net "GND")
		)
		(pad "131" smd rect
			(at -2.050034 52.274978 90)
			(size 0.519938 1.4986)
			(layers "F.Cu" "F.Mask" "F.Paste")
			(net "M_L_CPU0_SB_DQ<21>")
		)
		(pad "132" smd rect
			(at -2.050034 53.125116 90)
			(size 0.519938 1.4986)
			(layers "F.Cu" "F.Mask" "F.Paste")
			(net "GND")
		)
		(pad "133" smd rect
			(at -2.050034 53.975 90)
			(size 0.519938 1.4986)
			(layers "F.Cu" "F.Mask" "F.Paste")
			(net "M_L_CPU0_SB_DQ<24>")
		)
		(pad "134" smd rect
			(at -2.050034 54.824884 90)
			(size 0.519938 1.4986)
			(layers "F.Cu" "F.Mask" "F.Paste")
			(net "GND")
		)
		(pad "135" smd rect
			(at -2.050034 55.675022 90)
			(size 0.519938 1.4986)
			(layers "F.Cu" "F.Mask" "F.Paste")
			(net "M_L_CPU0_SB_DQ<25>")
		)
		(pad "136" smd rect
			(at -2.050034 56.524906 90)
			(size 0.519938 1.4986)
			(layers "F.Cu" "F.Mask" "F.Paste")
			(net "GND")
		)
		(pad "137" smd rect
			(at -2.050034 57.375044 90)
			(size 0.519938 1.4986)
			(layers "F.Cu" "F.Mask" "F.Paste")
			(net "M_L_CPU0_SB_DQS_DP<3>")
		)
		(pad "138" smd rect
			(at -2.050034 58.224928 90)
			(size 0.519938 1.4986)
			(layers "F.Cu" "F.Mask" "F.Paste")
			(net "M_L_CPU0_SB_DQS_DN<3>")
		)
	)
)
